# S9S_MB_2U (Grand Teton) — schematic netlist excerpt (pin names and nets, part order shuffled) for the footprints in the layout excerpt that follows; sources: Cadence DE-HDL packaged netlist, KiCad conversion of 03242023_DA0F0TMBIJ0_F0T_Motherboard_J_brd_V01_OCP.brd

R4289  Q_RES  4.7K 1% EMPTY  pkg 0402LF  page 169 : A = P3V3_AUX ; B = FM_USB3_1_RXDET_EN
R897  Q_RES  33.2 1% CHIP  pkg 0402LF  page 114 : A = PWRGD_CHC_CPU1_DIMM1 ; B = PWRGD_FAIL_CPU1_CD

(kicad_pcb
	(version 20260206)
	(generator "pcbnew")
	(generator_version "10.0")
	(general
		(thickness 1.6)
		(legacy_teardrops no)
	)
	(paper "A4")
	(title_block
		(title "03242023_DA0F0TMBIJ0_F0T_Motherboard_J_brd_V01_OCP.brd")
		(comment 1 "Grand Teton / footprints 5895-5896 of 6105")
	)
	(layers
		(0 "F.Cu" signal "TOP")
		(4 "In1.Cu" signal "GND")
		(6 "In2.Cu" signal "IN1")
		(8 "In3.Cu" signal "GND1")
		(10 "In4.Cu" signal "IN2")
		(12 "In5.Cu" signal "GND2")
		(14 "In6.Cu" signal "IN3")
		(16 "In7.Cu" signal "GND3")
		(18 "In8.Cu" signal "VCC")
		(20 "In9.Cu" signal "VCC1")
		(22 "In10.Cu" signal "GND4")
		(24 "In11.Cu" signal "IN4")
		(26 "In12.Cu" signal "GND5")
		(28 "In13.Cu" signal "IN5")
		(30 "In14.Cu" signal "GND6")
		(32 "In15.Cu" signal "IN6")
		(34 "In16.Cu" signal "GND7")
		(2 "B.Cu" signal "BOTTOM")
		(9 "F.Adhes" user "F.Adhesive")
		(11 "B.Adhes" user "B.Adhesive")
		(13 "F.Paste" user "Package Geometry/Pastemask Top")
		(15 "B.Paste" user "Package Geometry/Pastemask Bottom")
		(5 "F.SilkS" user "Ref Des/Silkscreen Top")
		(7 "B.SilkS" user "Ref Des/Silkscreen Bottom")
		(1 "F.Mask" user "Board Geometry/Soldermask Top")
		(3 "B.Mask" user "Board Geometry/Soldermask Bottom")
		(17 "Dwgs.User" user "User.Drawings")
		(19 "Cmts.User" user "User.Comments")
		(21 "Eco1.User" user "User.Eco1")
		(23 "Eco2.User" user "User.Eco2")
		(25 "Edge.Cuts" user "Board Geometry/Outline")
		(27 "Margin" user)
		(31 "F.CrtYd" user "Package Geometry/Place Bound Top")
		(29 "B.CrtYd" user "Package Geometry/Place Bound Bottom")
		(35 "F.Fab" user "Ref Des/Assembly Top")
		(33 "B.Fab" user "Ref Des/Assembly Bottom")
	)
	(footprint ""
		(layer "B.Cu")
		(at 27.304746 -319.268856 180)
		(property "Reference" "R897"
			(at 0 0 0)
			(layer "B.SilkS")
			(hide yes)
			(effects
				(font
					(size 1.27 1.27)
				)
				(justify mirror)
			)
		)
		(property "Value" ""
			(at 0 0 0)
			(layer "B.Fab")
			(effects
				(font
					(size 1.27 1.27)
				)
				(justify mirror)
			)
		)
		(duplicate_pad_numbers_are_jumpers no)
		(fp_line
			(start 0.7874 0.4064)
			(end 0.7874 -0.4064)
			(stroke
				(width 0.1524)
				(type default)
			)
			(layer "B.SilkS")
		)
		(fp_line
			(start 0.7874 -0.4064)
			(end -0.7874 -0.4064)
			(stroke
				(width 0.1524)
				(type default)
			)
			(layer "B.SilkS")
		)
		(fp_line
			(start -0.7874 0.4064)
			(end 0.7874 0.4064)
			(stroke
				(width 0.1524)
				(type default)
			)
			(layer "B.SilkS")
		)
		(fp_line
			(start -0.7874 -0.4064)
			(end -0.7874 0.4064)
			(stroke
				(width 0.1524)
				(type default)
			)
			(layer "B.SilkS")
		)
		(fp_line
			(start 0.67945 0.3048)
			(end 0.67945 -0.305054)
			(stroke
				(width 0.1)
				(type default)
			)
			(layer "B.Fab")
		)
		(fp_line
			(start 0.67945 -0.305054)
			(end 0.12065 -0.305054)
			(stroke
				(width 0.1)
				(type default)
			)
			(layer "B.Fab")
		)
		(fp_line
			(start 0.12065 0.3048)
			(end 0.67945 0.3048)
			(stroke
				(width 0.1)
				(type default)
			)
			(layer "B.Fab")
		)
		(fp_line
			(start 0.12065 0.2794)
			(end 0.12065 0.3048)
			(stroke
				(width 0.1)
				(type default)
			)
			(layer "B.Fab")
		)
		(fp_line
			(start 0.12065 -0.2794)
			(end -0.12065 -0.2794)
			(stroke
				(width 0.1)
				(type default)
			)
			(layer "B.Fab")
		)
		(fp_line
			(start 0.12065 -0.305054)
			(end 0.12065 -0.2794)
			(stroke
				(width 0.1)
				(type default)
			)
			(layer "B.Fab")
		)
		(fp_line
			(start -0.120396 0.3048)
			(end -0.120396 0.2794)
			(stroke
				(width 0.1)
				(type default)
			)
			(layer "B.Fab")
		)
		(fp_line
			(start -0.120396 0.2794)
			(end 0.12065 0.2794)
			(stroke
				(width 0.1)
				(type default)
			)
			(layer "B.Fab")
		)
		(fp_line
			(start -0.12065 -0.2794)
			(end -0.12065 -0.3048)
			(stroke
				(width 0.1)
				(type default)
			)
			(layer "B.Fab")
		)
		(fp_line
			(start -0.12065 -0.3048)
			(end -0.67945 -0.3048)
			(stroke
				(width 0.1)
				(type default)
			)
			(layer "B.Fab")
		)
		(fp_line
			(start -0.67945 0.3048)
			(end -0.120396 0.3048)
			(stroke
				(width 0.1)
				(type default)
			)
			(layer "B.Fab")
		)
		(fp_line
			(start -0.67945 -0.3048)
			(end -0.67945 0.3048)
			(stroke
				(width 0.1)
				(type default)
			)
			(layer "B.Fab")
		)
		(pad "1" smd circle
			(at 0.40005 0)
			(size 0 0)
			(layers "B.Cu" "B.Mask" "B.Paste")
			(net "PWRGD_CHC_CPU1_DIMM1")
		)
		(pad "2" smd circle
			(at -0.40005 0)
			(size 0 0)
			(layers "B.Cu" "B.Mask" "B.Paste")
			(net "PWRGD_FAIL_CPU1_CD")
		)
	)
	(footprint ""
		(layer "B.Cu")
		(at 126.67742 -31.526988 90)
		(property "Reference" "R4289"
			(at 0 0 90)
			(layer "B.SilkS")
			(hide yes)
			(effects
				(font
					(size 1.27 1.27)
				)
				(justify mirror)
			)
		)
		(property "Value" ""
			(at 0 0 90)
			(layer "B.Fab")
			(effects
				(font
					(size 1.27 1.27)
				)
				(justify mirror)
			)
		)
		(duplicate_pad_numbers_are_jumpers no)
		(fp_line
			(start 0.7874 -0.4064)
			(end -0.7874 -0.4064)
			(stroke
				(width 0.1524)
				(type default)
			)
			(layer "B.SilkS")
		)
		(fp_line
			(start -0.7874 -0.4064)
			(end -0.7874 0.4064)
			(stroke
				(width 0.1524)
				(type default)
			)
			(layer "B.SilkS")
		)
		(fp_line
			(start 0.7874 0.4064)
			(end 0.7874 -0.4064)
			(stroke
				(width 0.1524)
				(type default)
			)
			(layer "B.SilkS")
		)
		(fp_line
			(start -0.7874 0.4064)
			(end 0.7874 0.4064)
			(stroke
				(width 0.1524)
				(type default)
			)
			(layer "B.SilkS")
		)
		(fp_line
			(start 0.67945 -0.305054)
			(end 0.12065 -0.305054)
			(stroke
				(width 0.1)
				(type default)
			)
			(layer "B.Fab")
		)
		(fp_line
			(start 0.12065 -0.305054)
			(end 0.12065 -0.2794)
			(stroke
				(width 0.1)
				(type default)
			)
			(layer "B.Fab")
		)
		(fp_line
			(start -0.12065 -0.3048)
			(end -0.67945 -0.3048)
			(stroke
				(width 0.1)
				(type default)
			)
			(layer "B.Fab")
		)
		(fp_line
			(start -0.67945 -0.3048)
			(end -0.67945 0.3048)
			(stroke
				(width 0.1)
				(type default)
			)
			(layer "B.Fab")
		)
		(fp_line
			(start 0.12065 -0.2794)
			(end -0.12065 -0.2794)
			(stroke
				(width 0.1)
				(type default)
			)
			(layer "B.Fab")
		)
		(fp_line
			(start -0.12065 -0.2794)
			(end -0.12065 -0.3048)
			(stroke
				(width 0.1)
				(type default)
			)
			(layer "B.Fab")
		)
		(fp_line
			(start 0.12065 0.2794)
			(end 0.12065 0.3048)
			(stroke
				(width 0.1)
				(type default)
			)
			(layer "B.Fab")
		)
		(fp_line
			(start -0.120396 0.2794)
			(end 0.12065 0.2794)
			(stroke
				(width 0.1)
				(type default)
			)
			(layer "B.Fab")
		)
		(fp_line
			(start 0.67945 0.3048)
			(end 0.67945 -0.305054)
			(stroke
				(width 0.1)
				(type default)
			)
			(layer "B.Fab")
		)
		(fp_line
			(start 0.12065 0.3048)
			(end 0.67945 0.3048)
			(stroke
				(width 0.1)
				(type default)
			)
			(layer "B.Fab")
		)
		(fp_line
			(start -0.120396 0.3048)
			(end -0.120396 0.2794)
			(stroke
				(width 0.1)
				(type default)
			)
			(layer "B.Fab")
		)
		(fp_line
			(start -0.67945 0.3048)
			(end -0.120396 0.3048)
			(stroke
				(width 0.1)
				(type default)
			)
			(layer "B.Fab")
		)
		(pad "1" smd circle
			(at 0.40005 0 270)
			(size 0 0)
			(layers "B.Cu" "B.Mask" "B.Paste")
			(net "P3V3_AUX")
		)
		(pad "2" smd circle
			(at -0.40005 0 270)
			(size 0 0)
			(layers "B.Cu" "B.Mask" "B.Paste")
			(net "FM_USB3_1_RXDET_EN")
		)
	)
)
